(kicad_pcb
	(version 20260206)
	(generator "pcbnew")
	(generator_version "10.0")
	(general
		(thickness 1.6)
		(legacy_teardrops no)
	)
	(paper "A4")
	(title_block
		(title "dpb — 14545-sa.0730WZS0815.brd")
		(comment 1 "Honey Badger (Wiwynn) / footprints 512-516 of 1066")
	)
	(layers
		(0 "F.Cu" signal "TOP")
		(4 "In1.Cu" signal "L2GND")
		(6 "In2.Cu" signal "L3")
		(8 "In3.Cu" signal "L4VCC")
		(10 "In4.Cu" signal "L5VCC")
		(12 "In5.Cu" signal "L6")
		(14 "In6.Cu" signal "L7GND")
		(2 "B.Cu" signal "BOTTOM")
		(9 "F.Adhes" user "F.Adhesive")
		(11 "B.Adhes" user "B.Adhesive")
		(13 "F.Paste" user "Package Geometry/Pastemask Top")
		(15 "B.Paste" user "Package Geometry/Pastemask Bottom")
		(5 "F.SilkS" user "Ref Des/Silkscreen Top")
		(7 "B.SilkS" user "Ref Des/Silkscreen Bottom")
		(1 "F.Mask" user "Board Geometry/Soldermask Top")
		(3 "B.Mask" user "Board Geometry/Soldermask Bottom")
		(17 "Dwgs.User" user "User.Drawings")
		(19 "Cmts.User" user "User.Comments")
		(21 "Eco1.User" user "User.Eco1")
		(23 "Eco2.User" user "User.Eco2")
		(25 "Edge.Cuts" user "Board Geometry/Outline")
		(27 "Margin" user)
		(31 "F.CrtYd" user "Package Geometry/Place Bound Top")
		(29 "B.CrtYd" user "Package Geometry/Place Bound Bottom")
		(35 "F.Fab" user "Ref Des/Assembly Top")
		(33 "B.Fab" user "Ref Des/Assembly Bottom")
	)
	(footprint ""
		(layer "F.Cu")
		(at 73.603358 -500.047514 90)
		(property "Reference" "U17"
			(at 0 0 90)
			(layer "F.SilkS")
			(hide yes)
			(effects
				(font
					(size 1.27 1.27)
				)
			)
		)
		(property "Value" "P2003EVG-GP"
			(at 0 -11.1252 90)
			(unlocked yes)
			(layer "F.Fab")
			(hide yes)
			(effects
				(font
					(size 1.016 1.016)
					(thickness 0.1524)
				)
			)
		)
		(property "Device Type" "SOIC8H79"
			(at 0 -12.6492 90)
			(unlocked yes)
			(layer "F.Fab")
			(hide yes)
			(effects
				(font
					(size 1.016 1.016)
					(thickness 0.1524)
				)
			)
		)
		(duplicate_pad_numbers_are_jumpers no)
		(fp_line
			(start 2.1336 -1.4224)
			(end -2.7432 -1.4224)
			(stroke
				(width 0.1524)
				(type default)
			)
			(layer "F.SilkS")
		)
		(fp_line
			(start -2.7432 -1.4224)
			(end -2.7432 1.4224)
			(stroke
				(width 0.1524)
				(type default)
			)
			(layer "F.SilkS")
		)
		(fp_line
			(start -2.7432 -0.508)
			(end -2.2352 0)
			(stroke
				(width 0.1524)
				(type default)
			)
			(layer "F.SilkS")
		)
		(fp_line
			(start -2.2352 0)
			(end -2.7432 0.508)
			(stroke
				(width 0.1524)
				(type default)
			)
			(layer "F.SilkS")
		)
		(fp_line
			(start 2.1336 1.4224)
			(end 2.1336 -1.4224)
			(stroke
				(width 0.1524)
				(type default)
			)
			(layer "F.SilkS")
		)
		(fp_line
			(start -2.7432 1.4224)
			(end 2.1336 1.4224)
			(stroke
				(width 0.1524)
				(type default)
			)
			(layer "F.SilkS")
		)
		(fp_line
			(start -2.6162 3.429)
			(end -2.6162 1.4732)
			(stroke
				(width 0.4064)
				(type default)
			)
			(layer "F.SilkS")
		)
		(fp_poly
			(pts
				(xy 2.2098 -1.4224) (xy 2.2098 1.4224) (xy -2.2225 1.4224) (xy -2.2225 -1.4224)
			)
			(stroke
				(width 0)
				(type default)
			)
			(fill yes)
			(layer "F.SilkS")
		)
		(fp_rect
			(start -2.4511 2.9972)
			(end 2.4511 -2.9972)
			(stroke
				(width 0)
				(type default)
			)
			(fill no)
			(layer "F.CrtYd")
		)
		(fp_poly
			(pts
				(xy -2.8194 3.6322) (xy -2.8194 -3.6322) (xy 2.8194 -3.6322) (xy 2.8194 -2.2987) (xy 2.4511 -2.2987)
				(xy 2.4511 -2.9972) (xy -2.4511 -2.9972) (xy -2.4511 2.9972) (xy 2.4511 2.9972) (xy 2.4511 -2.286)
				(xy 2.8194 -2.286) (xy 2.8194 3.6322)
			)
			(stroke
				(width 0)
				(type default)
			)
			(fill no)
			(layer "F.CrtYd")
		)
		(fp_rect
			(start -2.8194 3.6322)
			(end 2.8194 -3.6322)
			(stroke
				(width 0)
				(type default)
			)
			(fill no)
			(layer "F.Fab")
		)
		(pad "1" smd rect
			(at -1.905 2.54 90)
			(size 0.635 1.651)
			(layers "F.Cu" "F.Mask" "F.Paste")
			(net "P12V")
		)
		(pad "2" smd rect
			(at -0.635 2.54 90)
			(size 0.635 1.651)
			(layers "F.Cu" "F.Mask" "F.Paste")
			(net "P12V")
		)
		(pad "3" smd rect
			(at 0.635 2.54 90)
			(size 0.635 1.651)
			(layers "F.Cu" "F.Mask" "F.Paste")
			(net "P12V")
		)
		(pad "4" smd rect
			(at 1.905 2.54 90)
			(size 0.635 1.651)
			(layers "F.Cu" "F.Mask" "F.Paste")
			(net "SW_HDD5_N")
		)
		(pad "5" smd rect
			(at 1.905 -2.54 90)
			(size 0.635 1.651)
			(layers "F.Cu" "F.Mask" "F.Paste")
			(net "P12V_HDD5")
		)
		(pad "6" smd rect
			(at 0.635 -2.54 90)
			(size 0.635 1.651)
			(layers "F.Cu" "F.Mask" "F.Paste")
			(net "P12V_HDD5")
		)
		(pad "7" smd rect
			(at -0.635 -2.54 90)
			(size 0.635 1.651)
			(layers "F.Cu" "F.Mask" "F.Paste")
			(net "P12V_HDD5")
		)
		(pad "8" smd rect
			(at -1.905 -2.54 90)
			(size 0.635 1.651)
			(layers "F.Cu" "F.Mask" "F.Paste")
			(net "P12V_HDD5")
		)
	)
	(footprint ""
		(layer "F.Cu")
		(at 193.167 -281.686)
		(property "Reference" "C141"
			(at 0 0 0)
			(layer "F.SilkS")
			(hide yes)
			(effects
				(font
					(size 1.27 1.27)
				)
			)
		)
		(property "Value" "SCD1U10V2KX-5GP"
			(at 1.1811 -2.7051 0)
			(unlocked yes)
			(layer "F.Fab")
			(hide yes)
			(effects
				(font
					(size 1.016 1.016)
					(thickness 0.1524)
				)
			)
		)
		(property "Device Type" "C402H22"
			(at 1.1811 -4.2291 0)
			(unlocked yes)
			(layer "F.Fab")
			(hide yes)
			(effects
				(font
					(size 1.016 1.016)
					(thickness 0.1524)
				)
			)
		)
		(duplicate_pad_numbers_are_jumpers no)
		(fp_rect
			(start -0.4318 0.9525)
			(end 0.4318 -0.9525)
			(stroke
				(width 0)
				(type default)
			)
			(fill no)
			(layer "F.CrtYd")
		)
		(fp_rect
			(start -0.4318 0.9525)
			(end 0.4318 -0.9525)
			(stroke
				(width 0)
				(type default)
			)
			(fill no)
			(layer "F.Fab")
		)
		(pad "1" smd custom
			(at 0 -0.4445)
			(size 0.1524 0.1524)
			(layers "F.Cu" "F.Mask" "F.Paste")
			(net "P3V3")
			(options
				(clearance outline)
				(anchor circle)
			)
			(primitives
				(gr_poly
					(pts
						(arc
							(start 0.3048 -0.2032)
							(mid 0.275042 -0.275042)
							(end 0.2032 -0.3048)
						)
						(arc
							(start -0.2032 -0.3048)
							(mid -0.275042 -0.275042)
							(end -0.3048 -0.2032)
						)
						(arc
							(start -0.3048 0.2032)
							(mid -0.275042 0.275042)
							(end -0.2032 0.3048)
						)
						(arc
							(start 0.2032 0.3048)
							(mid 0.275042 0.275042)
							(end 0.3048 0.2032)
						)
					)
					(width 0)
					(fill yes)
				)
			)
		)
		(pad "2" smd custom
			(at 0 0.4445)
			(size 0.1524 0.1524)
			(layers "F.Cu" "F.Mask" "F.Paste")
			(net "GND")
			(options
				(clearance outline)
				(anchor circle)
			)
			(primitives
				(gr_poly
					(pts
						(arc
							(start 0.3048 -0.2032)
							(mid 0.275042 -0.275042)
							(end 0.2032 -0.3048)
						)
						(arc
							(start -0.2032 -0.3048)
							(mid -0.275042 -0.275042)
							(end -0.3048 -0.2032)
						)
						(arc
							(start -0.3048 0.2032)
							(mid -0.275042 0.275042)
							(end -0.2032 0.3048)
						)
						(arc
							(start 0.2032 0.3048)
							(mid 0.275042 0.275042)
							(end 0.3048 0.2032)
						)
					)
					(width 0)
					(fill yes)
				)
			)
		)
	)
	(footprint ""
		(layer "F.Cu")
		(at 51.891946 -349.7072 90)
		(property "Reference" "Q40"
			(at 0 0 90)
			(layer "F.SilkS")
			(hide yes)
			(effects
				(font
					(size 1.27 1.27)
				)
			)
		)
		(property "Value" "PMBS3904-1-GP"
			(at 0 -9.0932 90)
			(unlocked yes)
			(layer "F.Fab")
			(hide yes)
			(effects
				(font
					(size 1.016 1.016)
					(thickness 0.1524)
				)
			)
		)
		(property "Device Type" "SOT-23-10H44"
			(at 0 -10.6172 90)
			(unlocked yes)
			(layer "F.Fab")
			(hide yes)
			(effects
				(font
					(size 1.016 1.016)
					(thickness 0.1524)
				)
			)
		)
		(duplicate_pad_numbers_are_jumpers no)
		(fp_line
			(start 1.651 -1.778)
			(end -1.651 -1.778)
			(stroke
				(width 0.1524)
				(type default)
			)
			(layer "F.SilkS")
		)
		(fp_line
			(start -1.651 -1.778)
			(end -1.651 1.778)
			(stroke
				(width 0.1524)
				(type default)
			)
			(layer "F.SilkS")
		)
		(fp_line
			(start 1.651 1.778)
			(end 1.651 -1.778)
			(stroke
				(width 0.1524)
				(type default)
			)
			(layer "F.SilkS")
		)
		(fp_line
			(start -1.651 1.778)
			(end 1.651 1.778)
			(stroke
				(width 0.1524)
				(type default)
			)
			(layer "F.SilkS")
		)
		(fp_line
			(start -0.9906 1.86309)
			(end -0.701294 2.15265)
			(stroke
				(width 0.0127)
				(type default)
			)
			(layer "F.SilkS")
		)
		(fp_line
			(start -0.994156 1.8669)
			(end -0.987044 1.8669)
			(stroke
				(width 0.0127)
				(type default)
			)
			(layer "F.SilkS")
		)
		(fp_line
			(start -1.003808 1.876552)
			(end -0.977646 1.876552)
			(stroke
				(width 0.0127)
				(type default)
			)
			(layer "F.SilkS")
		)
		(fp_line
			(start -0.635 1.8796)
			(end -1.7526 1.8796)
			(stroke
				(width 0.3302)
				(type default)
			)
			(layer "F.SilkS")
		)
		(fp_line
			(start -1.7526 1.8796)
			(end -1.7526 0.9906)
			(stroke
				(width 0.3302)
				(type default)
			)
			(layer "F.SilkS")
		)
		(fp_line
			(start -1.013206 1.88595)
			(end -0.967994 1.88595)
			(stroke
				(width 0.0127)
				(type default)
			)
			(layer "F.SilkS")
		)
		(fp_line
			(start -1.022858 1.895602)
			(end -0.958596 1.895602)
			(stroke
				(width 0.0127)
				(type default)
			)
			(layer "F.SilkS")
		)
		(fp_line
			(start -1.032256 1.905)
			(end -0.948944 1.905)
			(stroke
				(width 0.0127)
				(type default)
			)
			(layer "F.SilkS")
		)
		(fp_line
			(start -1.041908 1.914652)
			(end -0.939546 1.914652)
			(stroke
				(width 0.0127)
				(type default)
			)
			(layer "F.SilkS")
		)
		(fp_line
			(start -1.051306 1.92405)
			(end -0.929894 1.92405)
			(stroke
				(width 0.0127)
				(type default)
			)
			(layer "F.SilkS")
		)
		(fp_line
			(start -1.060958 1.933702)
			(end -0.920496 1.933702)
			(stroke
				(width 0.0127)
				(type default)
			)
			(layer "F.SilkS")
		)
		(fp_line
			(start -1.070356 1.9431)
			(end -0.910844 1.9431)
			(stroke
				(width 0.0127)
				(type default)
			)
			(layer "F.SilkS")
		)
		(fp_line
			(start -1.080008 1.952752)
			(end -0.901446 1.952752)
			(stroke
				(width 0.0127)
				(type default)
			)
			(layer "F.SilkS")
		)
		(fp_line
			(start -1.089406 1.96215)
			(end -0.891794 1.96215)
			(stroke
				(width 0.0127)
				(type default)
			)
			(layer "F.SilkS")
		)
		(fp_line
			(start -1.099058 1.971802)
			(end -0.882396 1.971802)
			(stroke
				(width 0.0127)
				(type default)
			)
			(layer "F.SilkS")
		)
		(fp_line
			(start -1.108456 1.9812)
			(end -0.872744 1.9812)
			(stroke
				(width 0.0127)
				(type default)
			)
			(layer "F.SilkS")
		)
		(fp_line
			(start -1.118108 1.990852)
			(end -0.863346 1.990852)
			(stroke
				(width 0.0127)
				(type default)
			)
			(layer "F.SilkS")
		)
		(fp_line
			(start -1.127506 2.00025)
			(end -0.853694 2.00025)
			(stroke
				(width 0.0127)
				(type default)
			)
			(layer "F.SilkS")
		)
		(fp_line
			(start -1.137158 2.009902)
			(end -0.844296 2.009902)
			(stroke
				(width 0.0127)
				(type default)
			)
			(layer "F.SilkS")
		)
		(fp_line
			(start -1.146556 2.0193)
			(end -0.834644 2.0193)
			(stroke
				(width 0.0127)
				(type default)
			)
			(layer "F.SilkS")
		)
		(fp_line
			(start -1.156208 2.028952)
			(end -0.825246 2.028952)
			(stroke
				(width 0.0127)
				(type default)
			)
			(layer "F.SilkS")
		)
		(fp_line
			(start -1.165606 2.03835)
			(end -0.815594 2.03835)
			(stroke
				(width 0.0127)
				(type default)
			)
			(layer "F.SilkS")
		)
		(fp_line
			(start -1.175258 2.048002)
			(end -0.806196 2.048002)
			(stroke
				(width 0.0127)
				(type default)
			)
			(layer "F.SilkS")
		)
		(fp_line
			(start -1.184656 2.0574)
			(end -0.796544 2.0574)
			(stroke
				(width 0.0127)
				(type default)
			)
			(layer "F.SilkS")
		)
		(fp_line
			(start -1.194308 2.067052)
			(end -0.787146 2.067052)
			(stroke
				(width 0.0127)
				(type default)
			)
			(layer "F.SilkS")
		)
		(fp_line
			(start -1.203706 2.07645)
			(end -0.777494 2.07645)
			(stroke
				(width 0.0127)
				(type default)
			)
			(layer "F.SilkS")
		)
		(fp_line
			(start -1.213358 2.086102)
			(end -0.768096 2.086102)
			(stroke
				(width 0.0127)
				(type default)
			)
			(layer "F.SilkS")
		)
		(fp_line
			(start -1.222756 2.0955)
			(end -0.758444 2.0955)
			(stroke
				(width 0.0127)
				(type default)
			)
			(layer "F.SilkS")
		)
		(fp_line
			(start -1.232408 2.105152)
			(end -0.749046 2.105152)
			(stroke
				(width 0.0127)
				(type default)
			)
			(layer "F.SilkS")
		)
		(fp_line
			(start -1.241806 2.11455)
			(end -0.739394 2.11455)
			(stroke
				(width 0.0127)
				(type default)
			)
			(layer "F.SilkS")
		)
		(fp_line
			(start -1.251458 2.124202)
			(end -0.729996 2.124202)
			(stroke
				(width 0.0127)
				(type default)
			)
			(layer "F.SilkS")
		)
		(fp_line
			(start -1.260856 2.1336)
			(end -0.720344 2.1336)
			(stroke
				(width 0.0127)
				(type default)
			)
			(layer "F.SilkS")
		)
		(fp_line
			(start -0.719074 2.145538)
			(end -1.265936 2.14122)
			(stroke
				(width 0.0127)
				(type default)
			)
			(layer "F.SilkS")
		)
		(fp_line
			(start -1.279398 2.152142)
			(end -0.9906 1.86309)
			(stroke
				(width 0.0127)
				(type default)
			)
			(layer "F.SilkS")
		)
		(fp_line
			(start -0.71628 2.15265)
			(end -1.26492 2.15265)
			(stroke
				(width 0.0127)
				(type default)
			)
			(layer "F.SilkS")
		)
		(fp_line
			(start -1.279144 2.15265)
			(end -0.701294 2.15265)
			(stroke
				(width 0.0127)
				(type default)
			)
			(layer "F.SilkS")
		)
		(fp_poly
			(pts
				(xy -1.285748 2.159) (xy -1.285748 1.8796) (xy -1.778 1.8796) (xy -1.778 -1.8796) (xy 1.778 -1.8796)
				(xy 1.778 1.8796) (xy -0.694944 1.8796) (xy -0.694944 2.159)
			)
			(stroke
				(width 0)
				(type default)
			)
			(fill no)
			(layer "F.CrtYd")
		)
		(fp_poly
			(pts
				(xy -1.285748 2.159) (xy -1.285748 1.8796) (xy -1.778 1.8796) (xy -1.778 -1.8796) (xy 1.778 -1.8796)
				(xy 1.778 1.8796) (xy -0.694944 1.8796) (xy -0.694944 2.159)
			)
			(stroke
				(width 0)
				(type default)
			)
			(fill no)
			(layer "F.Fab")
		)
		(pad "1" smd rect
			(at -0.98425 0.9525 90)
			(size 0.762 1.143)
			(layers "F.Cu" "F.Mask" "F.Paste")
			(net "FLT_HDD6_B")
		)
		(pad "2" smd rect
			(at 0.98425 0.9525 90)
			(size 0.762 1.143)
			(layers "F.Cu" "F.Mask" "F.Paste")
			(net "GND")
		)
		(pad "3" smd rect
			(at 0 -0.9525 90)
			(size 0.762 1.143)
			(layers "F.Cu" "F.Mask" "F.Paste")
			(net "DRIVE_ACT_6")
		)
	)
	(footprint ""
		(layer "F.Cu")
		(at 190.373 -497.84)
		(property "Reference" "R109"
			(at 0 0 0)
			(layer "F.SilkS")
			(hide yes)
			(effects
				(font
					(size 1.27 1.27)
				)
			)
		)
		(property "Value" "200KR2F-L-GP"
			(at 0.064008 -3.993896 0)
			(unlocked yes)
			(layer "F.Fab")
			(hide yes)
			(effects
				(font
					(size 1.016 1.016)
					(thickness 0.1524)
				)
			)
		)
		(property "Device Type" "R402H16"
			(at 0.064008 -5.517896 0)
			(unlocked yes)
			(layer "F.Fab")
			(hide yes)
			(effects
				(font
					(size 1.016 1.016)
					(thickness 0.1524)
				)
			)
		)
		(duplicate_pad_numbers_are_jumpers no)
		(fp_line
			(start -0.508 -0.9398)
			(end -0.508 0.9398)
			(stroke
				(width 0.1524)
				(type default)
			)
			(layer "F.SilkS")
		)
		(fp_line
			(start 0.508 -0.9398)
			(end -0.508 -0.9398)
			(stroke
				(width 0.1524)
				(type default)
			)
			(layer "F.SilkS")
		)
		(fp_rect
			(start -0.508 0.9398)
			(end 0.508 -0.9398)
			(stroke
				(width 0)
				(type default)
			)
			(fill no)
			(layer "F.CrtYd")
		)
		(fp_rect
			(start -0.508 0.9398)
			(end 0.508 -0.9398)
			(stroke
				(width 0)
				(type default)
			)
			(fill no)
			(layer "F.Fab")
		)
		(pad "1" smd custom
			(at 0 -0.4445)
			(size 0.1397 0.1397)
			(layers "F.Cu" "F.Mask" "F.Paste")
			(net "P12V")
			(options
				(clearance outline)
				(anchor circle)
			)
			(primitives
				(gr_poly
					(pts
						(arc
							(start -0.1778 -0.2794)
							(mid -0.249642 -0.249642)
							(end -0.2794 -0.1778)
						)
						(arc
							(start -0.2794 0.1778)
							(mid -0.249642 0.249642)
							(end -0.1778 0.2794)
						)
						(arc
							(start 0.1778 0.2794)
							(mid 0.249642 0.249642)
							(end 0.2794 0.1778)
						)
						(arc
							(start 0.2794 -0.1778)
							(mid 0.249642 -0.249642)
							(end 0.1778 -0.2794)
						)
					)
					(width 0)
					(fill yes)
				)
			)
		)
		(pad "2" smd custom
			(at 0 0.4445)
			(size 0.1397 0.1397)
			(layers "F.Cu" "F.Mask" "F.Paste")
			(net "SW_HDD0_P")
			(options
				(clearance outline)
				(anchor circle)
			)
			(primitives
				(gr_poly
					(pts
						(arc
							(start -0.1778 -0.2794)
							(mid -0.249642 -0.249642)
							(end -0.2794 -0.1778)
						)
						(arc
							(start -0.2794 0.1778)
							(mid -0.249642 0.249642)
							(end -0.1778 0.2794)
						)
						(arc
							(start 0.1778 0.2794)
							(mid 0.249642 0.249642)
							(end 0.2794 0.1778)
						)
						(arc
							(start 0.2794 -0.1778)
							(mid 0.249642 -0.249642)
							(end 0.1778 -0.2794)
						)
					)
					(width 0)
					(fill yes)
				)
			)
		)
	)
	(footprint ""
		(layer "F.Cu")
		(at 217.635582 -275.816568)
		(property "Reference" "C147"
			(at 0 0 0)
			(layer "F.SilkS")
			(hide yes)
			(effects
				(font
					(size 1.27 1.27)
				)
			)
		)
		(property "Value" "SCD01U50V2KX-1GP"
			(at 1.1811 -2.7051 0)
			(unlocked yes)
			(layer "F.Fab")
			(hide yes)
			(effects
				(font
					(size 1.016 1.016)
					(thickness 0.1524)
				)
			)
		)
		(property "Device Type" "C402H22"
			(at 1.1811 -4.2291 0)
			(unlocked yes)
			(layer "F.Fab")
			(hide yes)
			(effects
				(font
					(size 1.016 1.016)
					(thickness 0.1524)
				)
			)
		)
		(duplicate_pad_numbers_are_jumpers no)
		(fp_rect
			(start -0.4318 0.9525)
			(end 0.4318 -0.9525)
			(stroke
				(width 0)
				(type default)
			)
			(fill no)
			(layer "F.CrtYd")
		)
		(fp_rect
			(start -0.4318 0.9525)
			(end 0.4318 -0.9525)
			(stroke
				(width 0)
				(type default)
			)
			(fill no)
			(layer "F.Fab")
		)
		(pad "1" smd custom
			(at 0 -0.4445)
			(size 0.1524 0.1524)
			(layers "F.Cu" "F.Mask" "F.Paste")
			(net "HDD_PRSNT_NET2")
			(options
				(clearance outline)
				(anchor circle)
			)
			(primitives
				(gr_poly
					(pts
						(arc
							(start 0.3048 -0.2032)
							(mid 0.275042 -0.275042)
							(end 0.2032 -0.3048)
						)
						(arc
							(start -0.2032 -0.3048)
							(mid -0.275042 -0.275042)
							(end -0.3048 -0.2032)
						)
						(arc
							(start -0.3048 0.2032)
							(mid -0.275042 0.275042)
							(end -0.2032 0.3048)
						)
						(arc
							(start 0.2032 0.3048)
							(mid 0.275042 0.275042)
							(end 0.3048 0.2032)
						)
					)
					(width 0)
					(fill yes)
				)
			)
		)
		(pad "2" smd custom
			(at 0 0.4445)
			(size 0.1524 0.1524)
			(layers "F.Cu" "F.Mask" "F.Paste")
			(net "GND")
			(options
				(clearance outline)
				(anchor circle)
			)
			(primitives
				(gr_poly
					(pts
						(arc
							(start 0.3048 -0.2032)
							(mid 0.275042 -0.275042)
							(end 0.2032 -0.3048)
						)
						(arc
							(start -0.2032 -0.3048)
							(mid -0.275042 -0.275042)
							(end -0.3048 -0.2032)
						)
						(arc
							(start -0.3048 0.2032)
							(mid -0.275042 0.275042)
							(end -0.2032 0.3048)
						)
						(arc
							(start 0.2032 0.3048)
							(mid 0.275042 0.275042)
							(end 0.3048 0.2032)
						)
					)
					(width 0)
					(fill yes)
				)
			)
		)
	)
)
